# BASEBOARD_FAB2 (Tioga Pass) — schematic netlist excerpt (pin names and nets, part order shuffled) for the footprints in the layout excerpt that follows; sources: Cadence DE-HDL packaged netlist, KiCad conversion of Wiwynn_Tioga_Pass_MB.brd

C2A8  CAP  100UF 4V 20% X5R  pkg 0805  page 228 : A = PVDDQ_KLM ; B = GND
DS9A3  LED  IC  pkg 1NCLF  page 175 : C = FM_SPEAKER_PCH_N ; A = FM_BEEP_LED_P

(kicad_pcb
	(version 20260206)
	(generator "pcbnew")
	(generator_version "10.0")
	(general
		(thickness 1.6)
		(legacy_teardrops no)
	)
	(paper "A4")
	(title_block
		(title "Wiwynn_Tioga_Pass_MB.brd")
		(comment 1 "Tioga Pass / footprints 2285-2286 of 4770")
	)
	(layers
		(0 "F.Cu" signal "TOP")
		(4 "In1.Cu" signal "L2GND")
		(6 "In2.Cu" signal "L3")
		(8 "In3.Cu" signal "L4GND")
		(10 "In4.Cu" signal "L5")
		(12 "In5.Cu" signal "L6GND")
		(14 "In6.Cu" signal "L7VCC")
		(16 "In7.Cu" signal "L8VCC")
		(18 "In8.Cu" signal "L9GND")
		(20 "In9.Cu" signal "L10")
		(22 "In10.Cu" signal "L11GND")
		(24 "In11.Cu" signal "L12")
		(26 "In12.Cu" signal "L13GND")
		(2 "B.Cu" signal "BOTTOM")
		(9 "F.Adhes" user "F.Adhesive")
		(11 "B.Adhes" user "B.Adhesive")
		(13 "F.Paste" user "Package Geometry/Pastemask Top")
		(15 "B.Paste" user "Package Geometry/Pastemask Bottom")
		(5 "F.SilkS" user "Ref Des/Silkscreen Top")
		(7 "B.SilkS" user "Ref Des/Silkscreen Bottom")
		(1 "F.Mask" user "Board Geometry/Soldermask Top")
		(3 "B.Mask" user "Board Geometry/Soldermask Bottom")
		(17 "Dwgs.User" user "User.Drawings")
		(19 "Cmts.User" user "User.Comments")
		(21 "Eco1.User" user "User.Eco1")
		(23 "Eco2.User" user "User.Eco2")
		(25 "Edge.Cuts" user "Board Geometry/Outline")
		(27 "Margin" user)
		(31 "F.CrtYd" user "Package Geometry/Place Bound Top")
		(29 "B.CrtYd" user "Package Geometry/Place Bound Bottom")
		(35 "F.Fab" user "Ref Des/Assembly Top")
		(33 "B.Fab" user "Ref Des/Assembly Bottom")
	)
	(footprint ""
		(layer "F.Cu")
		(at 94.308168 -149.778212 90)
		(property "Reference" "C2A8"
			(at 0 0 90)
			(layer "F.SilkS")
			(hide yes)
			(effects
				(font
					(size 1.27 1.27)
				)
			)
		)
		(property "Value" ""
			(at 0 0 90)
			(layer "F.Fab")
			(effects
				(font
					(size 1.27 1.27)
				)
			)
		)
		(duplicate_pad_numbers_are_jumpers no)
		(fp_poly
			(pts
				(xy -0.7239 -0.2159) (xy 0.7239 -0.2159) (xy 0.7239 1.9939) (xy -0.7239 1.9939)
			)
			(stroke
				(width 0)
				(type default)
			)
			(fill no)
			(layer "F.CrtYd")
		)
		(fp_line
			(start 0.7239 -0.2159)
			(end -0.7239 -0.2159)
			(stroke
				(width 0.1)
				(type default)
			)
			(layer "F.Fab")
		)
		(fp_line
			(start -0.7239 -0.2159)
			(end -0.7239 1.9939)
			(stroke
				(width 0.1)
				(type default)
			)
			(layer "F.Fab")
		)
		(fp_line
			(start 0.7239 1.9939)
			(end 0.7239 -0.2159)
			(stroke
				(width 0.1)
				(type default)
			)
			(layer "F.Fab")
		)
		(fp_line
			(start -0.7239 1.9939)
			(end 0.7239 1.9939)
			(stroke
				(width 0.1)
				(type default)
			)
			(layer "F.Fab")
		)
		(pad "1" smd rect
			(at 0 0 90)
			(size 1.27 1.016)
			(layers "F.Cu" "F.Mask" "F.Paste")
			(net "PVDDQ_KLM")
		)
		(pad "2" smd rect
			(at 0 1.778 90)
			(size 1.27 1.016)
			(layers "F.Cu" "F.Mask" "F.Paste")
			(net "GND")
		)
		(zone
			(layer "F.Cu")
			(hatch none 0.5)
			(connect_pads
				(clearance 0)
			)
			(min_thickness 0.25)
			(keepout
				(tracks not_allowed)
				(vias allowed)
				(pads allowed)
				(copperpour not_allowed)
				(footprints allowed)
			)
			(placement
				(enabled no)
				(sheetname "")
			)
			(fill
				(thermal_gap 0.5)
				(thermal_bridge_width 0.5)
				(island_removal_mode 0)
			)
			(polygon
				(pts
					(xy 94.816168 -149.143212) (xy 94.816168 -150.413212) (xy 95.578168 -150.413212) (xy 95.578168 -149.143212)
				)
			)
		)
	)
	(footprint ""
		(layer "F.Cu")
		(at 499.872 -144.399)
		(property "Reference" "DS9A3"
			(at -1.33477 0.11684 90)
			(unlocked yes)
			(layer "F.SilkS")
			(effects
				(font
					(size 0.7874 0.5842)
					(thickness 0.1524)
				)
			)
		)
		(property "Value" ""
			(at 0 0 0)
			(layer "F.Fab")
			(effects
				(font
					(size 1.27 1.27)
				)
			)
		)
		(duplicate_pad_numbers_are_jumpers no)
		(fp_line
			(start -1.826006 1.143254)
			(end -1.345184 0.310388)
			(stroke
				(width 0.1524)
				(type default)
			)
			(layer "F.SilkS")
		)
		(fp_line
			(start -1.345184 -0.813054)
			(end -1.345184 0.310388)
			(stroke
				(width 0.1524)
				(type default)
			)
			(layer "F.SilkS")
		)
		(fp_line
			(start -1.345184 0.310388)
			(end -0.864362 1.143254)
			(stroke
				(width 0.1524)
				(type default)
			)
			(layer "F.SilkS")
		)
		(fp_line
			(start -1.345184 1.143254)
			(end -1.826006 1.143254)
			(stroke
				(width 0.1524)
				(type default)
			)
			(layer "F.SilkS")
		)
		(fp_line
			(start -1.345184 2.05486)
			(end -1.345184 1.143254)
			(stroke
				(width 0.1524)
				(type default)
			)
			(layer "F.SilkS")
		)
		(fp_line
			(start -0.864362 0.310388)
			(end -1.826006 0.310388)
			(stroke
				(width 0.1524)
				(type default)
			)
			(layer "F.SilkS")
		)
		(fp_line
			(start -0.864362 1.143254)
			(end -1.345184 1.143254)
			(stroke
				(width 0.1524)
				(type default)
			)
			(layer "F.SilkS")
		)
		(fp_poly
			(pts
				(xy -0.5715 2.2098) (xy -0.5715 0.2032) (xy 0.5715 0.2032) (xy 0.5715 0.6985)
				(arc
					(start 0.726948 0.6985)
					(mid 1.29058 0.932279)
					(end 1.524 1.49606)
				)
				(arc
					(start 1.524 2.05994)
					(mid 1.2904 2.6239)
					(end 0.72644 2.8575)
				)
				(xy 0.5715 2.8575) (xy 0.5715 3.3528) (xy -0.5715 3.3528)
			)
			(stroke
				(width 0)
				(type default)
			)
			(fill no)
			(layer "F.CrtYd")
		)
		(fp_line
			(start -1.837182 1.132078)
			(end -1.35636 0.299212)
			(stroke
				(width 0.1)
				(type default)
			)
			(layer "F.Fab")
		)
		(fp_line
			(start -1.35636 0.299212)
			(end -1.35636 -0.82423)
			(stroke
				(width 0.1)
				(type default)
			)
			(layer "F.Fab")
		)
		(fp_line
			(start -1.35636 0.299212)
			(end -0.875538 1.132078)
			(stroke
				(width 0.1)
				(type default)
			)
			(layer "F.Fab")
		)
		(fp_line
			(start -1.35636 1.132078)
			(end -1.35636 2.043684)
			(stroke
				(width 0.1)
				(type default)
			)
			(layer "F.Fab")
		)
		(fp_line
			(start -0.875538 0.299212)
			(end -1.837182 0.299212)
			(stroke
				(width 0.1)
				(type default)
			)
			(layer "F.Fab")
		)
		(fp_line
			(start -0.875538 1.132078)
			(end -1.837182 1.132078)
			(stroke
				(width 0.1)
				(type default)
			)
			(layer "F.Fab")
		)
		(fp_line
			(start -0.5715 0.2032)
			(end 0.5715 0.2032)
			(stroke
				(width 0.1)
				(type default)
			)
			(layer "F.Fab")
		)
		(fp_line
			(start -0.5715 0.7112)
			(end 0.5715 0.7112)
			(stroke
				(width 0.1)
				(type default)
			)
			(layer "F.Fab")
		)
		(fp_line
			(start -0.5715 2.8448)
			(end 0.5715 2.8448)
			(stroke
				(width 0.1)
				(type default)
			)
			(layer "F.Fab")
		)
		(fp_line
			(start -0.5715 3.3528)
			(end -0.5715 0.2032)
			(stroke
				(width 0.1)
				(type default)
			)
			(layer "F.Fab")
		)
		(fp_line
			(start 0.5715 0.2032)
			(end 0.5715 3.3528)
			(stroke
				(width 0.1)
				(type default)
			)
			(layer "F.Fab")
		)
		(fp_line
			(start 0.5715 2.8575)
			(end 0.72644 2.8575)
			(stroke
				(width 0.1)
				(type default)
			)
			(layer "F.Fab")
		)
		(fp_line
			(start 0.5715 3.3528)
			(end -0.5715 3.3528)
			(stroke
				(width 0.1)
				(type default)
			)
			(layer "F.Fab")
		)
		(fp_line
			(start 0.72644 0.6985)
			(end 0.5715 0.6985)
			(stroke
				(width 0.1)
				(type default)
			)
			(layer "F.Fab")
		)
		(fp_line
			(start 1.524 2.05994)
			(end 1.524 1.49606)
			(stroke
				(width 0.1)
				(type default)
			)
			(layer "F.Fab")
		)
		(fp_arc
			(start 0.72644 0.6985)
			(mid 1.290388 0.932112)
			(end 1.524 1.49606)
			(stroke
				(width 0.1)
				(type default)
			)
			(layer "F.Fab")
		)
		(fp_arc
			(start 1.524 2.05994)
			(mid 1.290388 2.623888)
			(end 0.72644 2.8575)
			(stroke
				(width 0.1)
				(type default)
			)
			(layer "F.Fab")
		)
		(pad "1" smd rect
			(at 0 0)
			(size 1.524 1.524)
			(layers "F.Cu" "F.Mask" "F.Paste")
			(net "FM_SPEAKER_PCH_N")
		)
		(pad "2" smd rect
			(at 0 3.556)
			(size 1.524 1.524)
			(layers "F.Cu" "F.Mask" "F.Paste")
			(net "FM_BEEP_LED_P")
		)
		(pad "3" smd rect
			(at -0.762 1.778)
			(size 0.889 0.889)
			(layers "F.Cu" "F.Mask" "F.Paste")
			(net "Net_6473")
		)
		(zone
			(layer "F.Cu")
			(hatch none 0.5)
			(connect_pads
				(clearance 0)
			)
			(min_thickness 0.25)
			(keepout
				(tracks allowed)
				(vias not_allowed)
				(pads allowed)
				(copperpour not_allowed)
				(footprints allowed)
			)
			(placement
				(enabled no)
				(sheetname "")
			)
			(fill
				(thermal_gap 0.5)
				(thermal_bridge_width 0.5)
				(island_removal_mode 0)
			)
			(polygon
				(pts
					(xy 500.4435 -143.5862) (xy 500.4435 -141.6558) (xy 499.3005 -141.6558) (xy 499.3005 -143.5862)
				)
			)
		)
	)
)
